# S9S_MB_2U (Grand Teton) — schematic netlist excerpt (pin names and nets, part order shuffled) for the footprints in the layout excerpt that follows; sources: Cadence DE-HDL packaged netlist, KiCad conversion of 03242023_DA0F0TMBIJ0_F0T_Motherboard_J_brd_V01_OCP.brd

C986  Q_CAP  10UF 6.3V 20% X6S  pkg C0402  page 74 : A = PVCCIN_CPU0 ; B = GND
C1000  Q_CAP  10UF 6.3V 20% X6S  pkg C0402  page 74 : A = PVCCIN_CPU0 ; B = GND

(kicad_pcb
	(version 20260206)
	(generator "pcbnew")
	(generator_version "10.0")
	(general
		(thickness 1.6)
		(legacy_teardrops no)
	)
	(paper "A4")
	(title_block
		(title "03242023_DA0F0TMBIJ0_F0T_Motherboard_J_brd_V01_OCP.brd")
		(comment 1 "Grand Teton / footprints 2939-2940 of 6105")
	)
	(layers
		(0 "F.Cu" signal "TOP")
		(4 "In1.Cu" signal "GND")
		(6 "In2.Cu" signal "IN1")
		(8 "In3.Cu" signal "GND1")
		(10 "In4.Cu" signal "IN2")
		(12 "In5.Cu" signal "GND2")
		(14 "In6.Cu" signal "IN3")
		(16 "In7.Cu" signal "GND3")
		(18 "In8.Cu" signal "VCC")
		(20 "In9.Cu" signal "VCC1")
		(22 "In10.Cu" signal "GND4")
		(24 "In11.Cu" signal "IN4")
		(26 "In12.Cu" signal "GND5")
		(28 "In13.Cu" signal "IN5")
		(30 "In14.Cu" signal "GND6")
		(32 "In15.Cu" signal "IN6")
		(34 "In16.Cu" signal "GND7")
		(2 "B.Cu" signal "BOTTOM")
		(9 "F.Adhes" user "F.Adhesive")
		(11 "B.Adhes" user "B.Adhesive")
		(13 "F.Paste" user "Package Geometry/Pastemask Top")
		(15 "B.Paste" user "Package Geometry/Pastemask Bottom")
		(5 "F.SilkS" user "Ref Des/Silkscreen Top")
		(7 "B.SilkS" user "Ref Des/Silkscreen Bottom")
		(1 "F.Mask" user "Board Geometry/Soldermask Top")
		(3 "B.Mask" user "Board Geometry/Soldermask Bottom")
		(17 "Dwgs.User" user "User.Drawings")
		(19 "Cmts.User" user "User.Comments")
		(21 "Eco1.User" user "User.Eco1")
		(23 "Eco2.User" user "User.Eco2")
		(25 "Edge.Cuts" user "Board Geometry/Outline")
		(27 "Margin" user)
		(31 "F.CrtYd" user "Package Geometry/Place Bound Top")
		(29 "B.CrtYd" user "Package Geometry/Place Bound Bottom")
		(35 "F.Fab" user "Ref Des/Assembly Top")
		(33 "B.Fab" user "Ref Des/Assembly Bottom")
	)
	(footprint ""
		(layer "F.Cu")
		(at 353.235514 -255.053846 90)
		(property "Reference" "C986"
			(at 0 0 90)
			(layer "F.SilkS")
			(hide yes)
			(effects
				(font
					(size 1.27 1.27)
				)
			)
		)
		(property "Value" ""
			(at 0 0 90)
			(layer "F.Fab")
			(effects
				(font
					(size 1.27 1.27)
				)
			)
		)
		(duplicate_pad_numbers_are_jumpers no)
		(fp_line
			(start 0.7874 -0.4064)
			(end 0.7874 0.4064)
			(stroke
				(width 0.1524)
				(type default)
			)
			(layer "F.SilkS")
		)
		(fp_line
			(start -0.7874 -0.4064)
			(end 0.7874 -0.4064)
			(stroke
				(width 0.1524)
				(type default)
			)
			(layer "F.SilkS")
		)
		(fp_line
			(start 0.7874 0.4064)
			(end -0.7874 0.4064)
			(stroke
				(width 0.1524)
				(type default)
			)
			(layer "F.SilkS")
		)
		(fp_line
			(start -0.7874 0.4064)
			(end -0.7874 -0.4064)
			(stroke
				(width 0.1524)
				(type default)
			)
			(layer "F.SilkS")
		)
		(fp_line
			(start -0.12065 -0.305054)
			(end -0.12065 -0.2794)
			(stroke
				(width 0.1)
				(type default)
			)
			(layer "F.Fab")
		)
		(fp_line
			(start -0.67945 -0.305054)
			(end -0.12065 -0.305054)
			(stroke
				(width 0.1)
				(type default)
			)
			(layer "F.Fab")
		)
		(fp_line
			(start 0.67945 -0.3048)
			(end 0.67945 0.3048)
			(stroke
				(width 0.1)
				(type default)
			)
			(layer "F.Fab")
		)
		(fp_line
			(start 0.12065 -0.3048)
			(end 0.67945 -0.3048)
			(stroke
				(width 0.1)
				(type default)
			)
			(layer "F.Fab")
		)
		(fp_line
			(start 0.12065 -0.2794)
			(end 0.12065 -0.3048)
			(stroke
				(width 0.1)
				(type default)
			)
			(layer "F.Fab")
		)
		(fp_line
			(start -0.12065 -0.2794)
			(end 0.12065 -0.2794)
			(stroke
				(width 0.1)
				(type default)
			)
			(layer "F.Fab")
		)
		(fp_line
			(start 0.120396 0.2794)
			(end -0.12065 0.2794)
			(stroke
				(width 0.1)
				(type default)
			)
			(layer "F.Fab")
		)
		(fp_line
			(start -0.12065 0.2794)
			(end -0.12065 0.3048)
			(stroke
				(width 0.1)
				(type default)
			)
			(layer "F.Fab")
		)
		(fp_line
			(start 0.67945 0.3048)
			(end 0.120396 0.3048)
			(stroke
				(width 0.1)
				(type default)
			)
			(layer "F.Fab")
		)
		(fp_line
			(start 0.120396 0.3048)
			(end 0.120396 0.2794)
			(stroke
				(width 0.1)
				(type default)
			)
			(layer "F.Fab")
		)
		(fp_line
			(start -0.12065 0.3048)
			(end -0.67945 0.3048)
			(stroke
				(width 0.1)
				(type default)
			)
			(layer "F.Fab")
		)
		(fp_line
			(start -0.67945 0.3048)
			(end -0.67945 -0.305054)
			(stroke
				(width 0.1)
				(type default)
			)
			(layer "F.Fab")
		)
		(pad "1" smd circle
			(at -0.40005 0 90)
			(size 0 0)
			(layers "F.Cu" "F.Mask" "F.Paste")
			(net "PVCCIN_CPU0")
		)
		(pad "2" smd circle
			(at 0.40005 0 90)
			(size 0 0)
			(layers "F.Cu" "F.Mask" "F.Paste")
			(net "GND")
		)
	)
	(footprint ""
		(layer "F.Cu")
		(at 364.50143 -255.053846 90)
		(property "Reference" "C1000"
			(at 0 0 90)
			(layer "F.SilkS")
			(hide yes)
			(effects
				(font
					(size 1.27 1.27)
				)
			)
		)
		(property "Value" ""
			(at 0 0 90)
			(layer "F.Fab")
			(effects
				(font
					(size 1.27 1.27)
				)
			)
		)
		(duplicate_pad_numbers_are_jumpers no)
		(fp_line
			(start 0.7874 -0.4064)
			(end 0.7874 0.4064)
			(stroke
				(width 0.1524)
				(type default)
			)
			(layer "F.SilkS")
		)
		(fp_line
			(start -0.7874 -0.4064)
			(end 0.7874 -0.4064)
			(stroke
				(width 0.1524)
				(type default)
			)
			(layer "F.SilkS")
		)
		(fp_line
			(start 0.7874 0.4064)
			(end -0.7874 0.4064)
			(stroke
				(width 0.1524)
				(type default)
			)
			(layer "F.SilkS")
		)
		(fp_line
			(start -0.7874 0.4064)
			(end -0.7874 -0.4064)
			(stroke
				(width 0.1524)
				(type default)
			)
			(layer "F.SilkS")
		)
		(fp_line
			(start -0.12065 -0.305054)
			(end -0.12065 -0.2794)
			(stroke
				(width 0.1)
				(type default)
			)
			(layer "F.Fab")
		)
		(fp_line
			(start -0.67945 -0.305054)
			(end -0.12065 -0.305054)
			(stroke
				(width 0.1)
				(type default)
			)
			(layer "F.Fab")
		)
		(fp_line
			(start 0.67945 -0.3048)
			(end 0.67945 0.3048)
			(stroke
				(width 0.1)
				(type default)
			)
			(layer "F.Fab")
		)
		(fp_line
			(start 0.12065 -0.3048)
			(end 0.67945 -0.3048)
			(stroke
				(width 0.1)
				(type default)
			)
			(layer "F.Fab")
		)
		(fp_line
			(start 0.12065 -0.2794)
			(end 0.12065 -0.3048)
			(stroke
				(width 0.1)
				(type default)
			)
			(layer "F.Fab")
		)
		(fp_line
			(start -0.12065 -0.2794)
			(end 0.12065 -0.2794)
			(stroke
				(width 0.1)
				(type default)
			)
			(layer "F.Fab")
		)
		(fp_line
			(start 0.120396 0.2794)
			(end -0.12065 0.2794)
			(stroke
				(width 0.1)
				(type default)
			)
			(layer "F.Fab")
		)
		(fp_line
			(start -0.12065 0.2794)
			(end -0.12065 0.3048)
			(stroke
				(width 0.1)
				(type default)
			)
			(layer "F.Fab")
		)
		(fp_line
			(start 0.67945 0.3048)
			(end 0.120396 0.3048)
			(stroke
				(width 0.1)
				(type default)
			)
			(layer "F.Fab")
		)
		(fp_line
			(start 0.120396 0.3048)
			(end 0.120396 0.2794)
			(stroke
				(width 0.1)
				(type default)
			)
			(layer "F.Fab")
		)
		(fp_line
			(start -0.12065 0.3048)
			(end -0.67945 0.3048)
			(stroke
				(width 0.1)
				(type default)
			)
			(layer "F.Fab")
		)
		(fp_line
			(start -0.67945 0.3048)
			(end -0.67945 -0.305054)
			(stroke
				(width 0.1)
				(type default)
			)
			(layer "F.Fab")
		)
		(pad "1" smd circle
			(at -0.40005 0 90)
			(size 0 0)
			(layers "F.Cu" "F.Mask" "F.Paste")
			(net "PVCCIN_CPU0")
		)
		(pad "2" smd circle
			(at 0.40005 0 90)
			(size 0 0)
			(layers "F.Cu" "F.Mask" "F.Paste")
			(net "GND")
		)
	)
)
